# S9S_MB_2U (Grand Teton) — schematic netlist excerpt (pin names and nets, part order shuffled) for the footprints in the layout excerpt that follows; sources: Cadence DE-HDL packaged netlist, KiCad conversion of 03242023_DA0F0TMBIJ0_F0T_Motherboard_J_brd_V01_OCP.brd

R4506  Q_RES  33.2 1% CHIP  pkg 0402LF  page 240 : A = SMB_SML0_3V3AUX_SCL ; B = SMB_SML0_3V3AUX_SCL_R1
R2497  Q_RES  1K 1% CHIP  pkg 0402LF  page 115 : A = PWRGD_FAIL_CPU1_GH ; B = PWRGD_FAIL_CPU1_GH_R1

(kicad_pcb
	(version 20260206)
	(generator "pcbnew")
	(generator_version "10.0")
	(general
		(thickness 1.6)
		(legacy_teardrops no)
	)
	(paper "A4")
	(title_block
		(title "03242023_DA0F0TMBIJ0_F0T_Motherboard_J_brd_V01_OCP.brd")
		(comment 1 "Grand Teton / footprints 5232-5233 of 6105")
	)
	(layers
		(0 "F.Cu" signal "TOP")
		(4 "In1.Cu" signal "GND")
		(6 "In2.Cu" signal "IN1")
		(8 "In3.Cu" signal "GND1")
		(10 "In4.Cu" signal "IN2")
		(12 "In5.Cu" signal "GND2")
		(14 "In6.Cu" signal "IN3")
		(16 "In7.Cu" signal "GND3")
		(18 "In8.Cu" signal "VCC")
		(20 "In9.Cu" signal "VCC1")
		(22 "In10.Cu" signal "GND4")
		(24 "In11.Cu" signal "IN4")
		(26 "In12.Cu" signal "GND5")
		(28 "In13.Cu" signal "IN5")
		(30 "In14.Cu" signal "GND6")
		(32 "In15.Cu" signal "IN6")
		(34 "In16.Cu" signal "GND7")
		(2 "B.Cu" signal "BOTTOM")
		(9 "F.Adhes" user "F.Adhesive")
		(11 "B.Adhes" user "B.Adhesive")
		(13 "F.Paste" user "Package Geometry/Pastemask Top")
		(15 "B.Paste" user "Package Geometry/Pastemask Bottom")
		(5 "F.SilkS" user "Ref Des/Silkscreen Top")
		(7 "B.SilkS" user "Ref Des/Silkscreen Bottom")
		(1 "F.Mask" user "Board Geometry/Soldermask Top")
		(3 "B.Mask" user "Board Geometry/Soldermask Bottom")
		(17 "Dwgs.User" user "User.Drawings")
		(19 "Cmts.User" user "User.Comments")
		(21 "Eco1.User" user "User.Eco1")
		(23 "Eco2.User" user "User.Eco2")
		(25 "Edge.Cuts" user "Board Geometry/Outline")
		(27 "Margin" user)
		(31 "F.CrtYd" user "Package Geometry/Place Bound Top")
		(29 "B.CrtYd" user "Package Geometry/Place Bound Bottom")
		(35 "F.Fab" user "Ref Des/Assembly Top")
		(33 "B.Fab" user "Ref Des/Assembly Bottom")
	)
	(footprint ""
		(layer "B.Cu")
		(at 215.840818 -317.06566 90)
		(property "Reference" "R2497"
			(at 0 0 90)
			(layer "B.SilkS")
			(hide yes)
			(effects
				(font
					(size 1.27 1.27)
				)
				(justify mirror)
			)
		)
		(property "Value" ""
			(at 0 0 90)
			(layer "B.Fab")
			(effects
				(font
					(size 1.27 1.27)
				)
				(justify mirror)
			)
		)
		(duplicate_pad_numbers_are_jumpers no)
		(fp_line
			(start 0.7874 -0.4064)
			(end -0.7874 -0.4064)
			(stroke
				(width 0.1524)
				(type default)
			)
			(layer "B.SilkS")
		)
		(fp_line
			(start -0.7874 -0.4064)
			(end -0.7874 0.4064)
			(stroke
				(width 0.1524)
				(type default)
			)
			(layer "B.SilkS")
		)
		(fp_line
			(start 0.7874 0.4064)
			(end 0.7874 -0.4064)
			(stroke
				(width 0.1524)
				(type default)
			)
			(layer "B.SilkS")
		)
		(fp_line
			(start -0.7874 0.4064)
			(end 0.7874 0.4064)
			(stroke
				(width 0.1524)
				(type default)
			)
			(layer "B.SilkS")
		)
		(fp_line
			(start 0.67945 -0.305054)
			(end 0.12065 -0.305054)
			(stroke
				(width 0.1)
				(type default)
			)
			(layer "B.Fab")
		)
		(fp_line
			(start 0.12065 -0.305054)
			(end 0.12065 -0.2794)
			(stroke
				(width 0.1)
				(type default)
			)
			(layer "B.Fab")
		)
		(fp_line
			(start -0.12065 -0.3048)
			(end -0.67945 -0.3048)
			(stroke
				(width 0.1)
				(type default)
			)
			(layer "B.Fab")
		)
		(fp_line
			(start -0.67945 -0.3048)
			(end -0.67945 0.3048)
			(stroke
				(width 0.1)
				(type default)
			)
			(layer "B.Fab")
		)
		(fp_line
			(start 0.12065 -0.2794)
			(end -0.12065 -0.2794)
			(stroke
				(width 0.1)
				(type default)
			)
			(layer "B.Fab")
		)
		(fp_line
			(start -0.12065 -0.2794)
			(end -0.12065 -0.3048)
			(stroke
				(width 0.1)
				(type default)
			)
			(layer "B.Fab")
		)
		(fp_line
			(start 0.12065 0.2794)
			(end 0.12065 0.3048)
			(stroke
				(width 0.1)
				(type default)
			)
			(layer "B.Fab")
		)
		(fp_line
			(start -0.120396 0.2794)
			(end 0.12065 0.2794)
			(stroke
				(width 0.1)
				(type default)
			)
			(layer "B.Fab")
		)
		(fp_line
			(start 0.67945 0.3048)
			(end 0.67945 -0.305054)
			(stroke
				(width 0.1)
				(type default)
			)
			(layer "B.Fab")
		)
		(fp_line
			(start 0.12065 0.3048)
			(end 0.67945 0.3048)
			(stroke
				(width 0.1)
				(type default)
			)
			(layer "B.Fab")
		)
		(fp_line
			(start -0.120396 0.3048)
			(end -0.120396 0.2794)
			(stroke
				(width 0.1)
				(type default)
			)
			(layer "B.Fab")
		)
		(fp_line
			(start -0.67945 0.3048)
			(end -0.120396 0.3048)
			(stroke
				(width 0.1)
				(type default)
			)
			(layer "B.Fab")
		)
		(pad "1" smd circle
			(at 0.40005 0 270)
			(size 0 0)
			(layers "B.Cu" "B.Mask" "B.Paste")
			(net "PWRGD_FAIL_CPU1_GH")
		)
		(pad "2" smd circle
			(at -0.40005 0 270)
			(size 0 0)
			(layers "B.Cu" "B.Mask" "B.Paste")
			(net "PWRGD_FAIL_CPU1_GH_R1")
		)
	)
	(footprint ""
		(layer "B.Cu")
		(at 162.306 -13.426948 90)
		(property "Reference" "R4506"
			(at 0 0 90)
			(layer "B.SilkS")
			(hide yes)
			(effects
				(font
					(size 1.27 1.27)
				)
				(justify mirror)
			)
		)
		(property "Value" ""
			(at 0 0 90)
			(layer "B.Fab")
			(effects
				(font
					(size 1.27 1.27)
				)
				(justify mirror)
			)
		)
		(duplicate_pad_numbers_are_jumpers no)
		(fp_line
			(start 0.7874 -0.4064)
			(end -0.7874 -0.4064)
			(stroke
				(width 0.1524)
				(type default)
			)
			(layer "B.SilkS")
		)
		(fp_line
			(start -0.7874 -0.4064)
			(end -0.7874 0.4064)
			(stroke
				(width 0.1524)
				(type default)
			)
			(layer "B.SilkS")
		)
		(fp_line
			(start 0.7874 0.4064)
			(end 0.7874 -0.4064)
			(stroke
				(width 0.1524)
				(type default)
			)
			(layer "B.SilkS")
		)
		(fp_line
			(start -0.7874 0.4064)
			(end 0.7874 0.4064)
			(stroke
				(width 0.1524)
				(type default)
			)
			(layer "B.SilkS")
		)
		(fp_line
			(start 0.67945 -0.305054)
			(end 0.12065 -0.305054)
			(stroke
				(width 0.1)
				(type default)
			)
			(layer "B.Fab")
		)
		(fp_line
			(start 0.12065 -0.305054)
			(end 0.12065 -0.2794)
			(stroke
				(width 0.1)
				(type default)
			)
			(layer "B.Fab")
		)
		(fp_line
			(start -0.12065 -0.3048)
			(end -0.67945 -0.3048)
			(stroke
				(width 0.1)
				(type default)
			)
			(layer "B.Fab")
		)
		(fp_line
			(start -0.67945 -0.3048)
			(end -0.67945 0.3048)
			(stroke
				(width 0.1)
				(type default)
			)
			(layer "B.Fab")
		)
		(fp_line
			(start 0.12065 -0.2794)
			(end -0.12065 -0.2794)
			(stroke
				(width 0.1)
				(type default)
			)
			(layer "B.Fab")
		)
		(fp_line
			(start -0.12065 -0.2794)
			(end -0.12065 -0.3048)
			(stroke
				(width 0.1)
				(type default)
			)
			(layer "B.Fab")
		)
		(fp_line
			(start 0.12065 0.2794)
			(end 0.12065 0.3048)
			(stroke
				(width 0.1)
				(type default)
			)
			(layer "B.Fab")
		)
		(fp_line
			(start -0.120396 0.2794)
			(end 0.12065 0.2794)
			(stroke
				(width 0.1)
				(type default)
			)
			(layer "B.Fab")
		)
		(fp_line
			(start 0.67945 0.3048)
			(end 0.67945 -0.305054)
			(stroke
				(width 0.1)
				(type default)
			)
			(layer "B.Fab")
		)
		(fp_line
			(start 0.12065 0.3048)
			(end 0.67945 0.3048)
			(stroke
				(width 0.1)
				(type default)
			)
			(layer "B.Fab")
		)
		(fp_line
			(start -0.120396 0.3048)
			(end -0.120396 0.2794)
			(stroke
				(width 0.1)
				(type default)
			)
			(layer "B.Fab")
		)
		(fp_line
			(start -0.67945 0.3048)
			(end -0.120396 0.3048)
			(stroke
				(width 0.1)
				(type default)
			)
			(layer "B.Fab")
		)
		(pad "1" smd circle
			(at 0.40005 0 270)
			(size 0 0)
			(layers "B.Cu" "B.Mask" "B.Paste")
			(net "SMB_SML0_3V3AUX_SCL")
		)
		(pad "2" smd circle
			(at -0.40005 0 270)
			(size 0 0)
			(layers "B.Cu" "B.Mask" "B.Paste")
			(net "SMB_SML0_3V3AUX_SCL_R1")
		)
	)
)
